#ISCELL
  mstr_misc dns *
  *
#ISCELL
  pure_quanta quanta_title_block_c *
  *
#ISCELL
  standard offpage *
  page168_i1
#CELL
  pure_quanta q_res *
  page168_i10
#ISCELL
  standard offpage *
  page168_i100
#ISCELL
  standard offpage *
  page168_i101
#ISCELL
  standard offpage *
  page168_i102
#ISCELL
  standard offpage *
  page168_i103
#ISCELL
  standard offpage *
  page168_i104
#ISCELL
  standard offpage *
  page168_i105
#ISCELL
  pure_quanta_power universal_gnd *
  page168_i106
#CELL
  pure_quanta q_res *
  page168_i107
#CELL
  pure_quanta q_res *
  page168_i108
#ISCELL
  pure_quanta_power universal_gnd *
  page168_i109
#ISCELL
  pure_quanta_power vcc_core *
  page168_i11
#ISCELL
  pure_quanta_power universal_gnd *
  page168_i110
#CELL
  pure_quanta q_res *
  page168_i111
#ISCELL
  standard offpage *
  page168_i112
#ISCELL
  standard offpage *
  page168_i113
#ISCELL
  standard offpage *
  page168_i114
#ISCELL
  standard offpage *
  page168_i115
#ISCELL
  standard offpage *
  page168_i116
#ISCELL
  pure_quanta_power universal_gnd *
  page168_i117
#CELL
  pure_quanta q_cap *
  page168_i118
#ISCELL
  pure_quanta_power universal_gnd *
  page168_i119
#ISCELL
  pure_quanta_power universal_gnd *
  page168_i12
#CELL
  pure_quanta q_cap *
  page168_i120
#ISCELL
  standard offpage *
  page168_i121
#ISCELL
  standard offpage *
  page168_i122
#ISCELL
  standard offpage *
  page168_i123
#ISCELL
  standard offpage *
  page168_i124
#ISCELL
  standard offpage *
  page168_i125
#ISCELL
  standard offpage *
  page168_i126
#ISCELL
  standard offpage *
  page168_i127
#ISCELL
  pure_quanta_power universal_gnd *
  page168_i128
#CELL
  pure_quanta q_cap *
  page168_i129
#CELL
  pure_quanta q_cap *
  page168_i13
#ISCELL
  pure_quanta_power universal_gnd *
  page168_i130
#CELL
  pure_quanta q_cap *
  page168_i131
#ISCELL
  standard offpage *
  page168_i132
#CELL
  pure_quanta q_res *
  page168_i133
#ISCELL
  pure_quanta_power vcc_core *
  page168_i134
#CELL
  pure_quanta raa229620gnpha0 *
  page168_i135
#CELL
  pure_quanta q_res *
  page168_i136
#ISCELL
  pure_quanta_power universal_gnd *
  page168_i137
#CELL
  pure_quanta q_cap *
  page168_i138
#CELL
  pure_quanta q_cap *
  page168_i139
#ISCELL
  pure_quanta_power vcc_core *
  page168_i14
#ISCELL
  pure_quanta_power universal_gnd *
  page168_i140
#ISCELL
  pure_quanta_power universal_gnd *
  page168_i141
#CELL
  pure_quanta q_cap *
  page168_i142
#CELL
  pure_quanta conn3_210hp1030br1 *
  page168_i143
#ISCELL
  standard offpage *
  page168_i144
#ISCELL
  pure_quanta_power universal_gnd *
  page168_i145
#ISCELL
  standard offpage *
  page168_i146
#CELL
  pure_quanta q_res *
  page168_i147
#CELL
  pure_quanta q_res *
  page168_i148
#CELL
  pure_quanta q_res *
  page168_i15
#ISCELL
  standard offpage *
  page168_i16
#CELL
  pure_quanta mosfet_n *
  page168_i17
#CELL
  pure_quanta q_res *
  page168_i18
#CELL
  pure_quanta mosfet_pch_gds_esd_protected *
  page168_i19
#CELL
  pure_quanta q_res *
  page168_i2
#ISCELL
  pure_quanta_power universal_gnd *
  page168_i20
#CELL
  pure_quanta q_res *
  page168_i21
#ISCELL
  pure_quanta_power universal_gnd *
  page168_i22
#CELL
  pure_quanta q_cap *
  page168_i23
#CELL
  pure_quanta q_res *
  page168_i24
#ISCELL
  pure_quanta_power vcc_core *
  page168_i25
#ISCELL
  pure_quanta_power universal_gnd *
  page168_i26
#CELL
  pure_quanta q_res *
  page168_i27
#CELL
  pure_quanta q_res *
  page168_i28
#ISCELL
  pure_quanta_power vcc_core *
  page168_i29
#ISCELL
  pure_quanta_power universal_gnd *
  page168_i3
#ISCELL
  pure_quanta_power vcc_core *
  page168_i30
#ISCELL
  pure_quanta_power vcc_core *
  page168_i31
#ISCELL
  standard offpage *
  page168_i32
#ISCELL
  standard offpage *
  page168_i33
#ISCELL
  standard offpage *
  page168_i34
#ISCELL
  standard offpage *
  page168_i35
#CELL
  pure_quanta q_res *
  page168_i36
#ISCELL
  pure_quanta_power universal_gnd *
  page168_i37
#ISCELL
  standard offpage *
  page168_i38
#ISCELL
  standard offpage *
  page168_i39
#CELL
  pure_quanta q_res *
  page168_i4
#CELL
  pure_quanta q_res *
  page168_i40
#ISCELL
  pure_quanta_power vcc_core *
  page168_i41
#CELL
  pure_quanta q_res *
  page168_i42
#ISCELL
  pure_quanta_power vcc_core *
  page168_i43
#CELL
  pure_quanta q_res *
  page168_i44
#ISCELL
  pure_quanta_power universal_gnd *
  page168_i45
#ISCELL
  pure_quanta_power universal_gnd *
  page168_i46
#CELL
  pure_quanta q_res *
  page168_i47
#CELL
  pure_quanta q_res *
  page168_i48
#ISCELL
  pure_quanta_power universal_gnd *
  page168_i49
#ISCELL
  pure_quanta_power universal_gnd *
  page168_i5
#CELL
  pure_quanta q_cap *
  page168_i50
#CELL
  pure_quanta q_cap *
  page168_i51
#CELL
  pure_quanta q_cap *
  page168_i52
#ISCELL
  pure_quanta_power universal_gnd *
  page168_i53
#CELL
  pure_quanta q_res *
  page168_i54
#ISCELL
  pure_quanta_power universal_gnd *
  page168_i55
#ISCELL
  pure_quanta_power universal_gnd *
  page168_i56
#CELL
  pure_quanta q_res *
  page168_i57
#CELL
  pure_quanta q_res *
  page168_i58
#CELL
  pure_quanta q_res *
  page168_i59
#CELL
  pure_quanta q_res *
  page168_i6
#CELL
  pure_quanta q_cap *
  page168_i60
#CELL
  pure_quanta q_res *
  page168_i61
#CELL
  pure_quanta q_cap *
  page168_i62
#ISCELL
  pure_quanta_power universal_gnd *
  page168_i63
#CELL
  pure_quanta q_cap *
  page168_i64
#ISCELL
  pure_quanta_power universal_gnd *
  page168_i65
#CELL
  pure_quanta q_cap *
  page168_i66
#ISCELL
  pure_quanta_power universal_gnd *
  page168_i67
#CELL
  pure_quanta q_cap *
  page168_i68
#CELL
  pure_quanta q_res *
  page168_i69
#ISCELL
  standard offpage *
  page168_i7
#CELL
  pure_quanta q_res *
  page168_i70
#CELL
  pure_quanta q_res *
  page168_i71
#CELL
  pure_quanta q_res *
  page168_i72
#ISCELL
  pure_quanta_power vcc_core *
  page168_i73
#ISCELL
  standard offpage *
  page168_i74
#ISCELL
  standard offpage *
  page168_i75
#ISCELL
  standard offpage *
  page168_i76
#ISCELL
  standard offpage *
  page168_i79
#ISCELL
  standard offpage *
  page168_i8
#ISCELL
  standard offpage *
  page168_i80
#ISCELL
  pure_quanta_power vcc_core *
  page168_i81
#CELL
  pure_quanta q_res *
  page168_i82
#CELL
  pure_quanta q_res *
  page168_i83
#CELL
  pure_quanta q_res *
  page168_i84
#CELL
  pure_quanta q_res *
  page168_i85
#CELL
  pure_quanta q_res *
  page168_i86
#CELL
  pure_quanta q_res *
  page168_i87
#CELL
  pure_quanta q_res *
  page168_i88
#CELL
  pure_quanta q_res *
  page168_i89
#ISCELL
  standard offpage *
  page168_i9
#CELL
  pure_quanta q_cap *
  page168_i90
#ISCELL
  pure_quanta_power universal_gnd *
  page168_i91
#CELL
  pure_quanta q_cap *
  page168_i92
#ISCELL
  pure_quanta_power universal_gnd *
  page168_i93
#ISCELL
  pure_quanta_power universal_gnd *
  page168_i94
#CELL
  pure_quanta q_cap *
  page168_i95
#ISCELL
  standard offpage *
  page168_i96
#ISCELL
  pure_quanta_power universal_gnd *
  page168_i97
#CELL
  pure_quanta q_cap *
  page168_i98
#ISCELL
  standard offpage *
  page168_i99
